# S9S_MB_2U (Grand Teton) — schematic netlist excerpt (pin names and nets, part order shuffled) for the footprints in the layout excerpt that follows; sources: Cadence DE-HDL packaged netlist, KiCad conversion of 03242023_DA0F0TMBIJ0_F0T_Motherboard_J_brd_V01_OCP.brd

U263  INA230AIRGTR  IC  pkg QFN16_THXI  page 172
  A1  = INA230_3_A1
  A0  = INA230_3_A0
  ALERT  = OCP_V3_2_P3V3_ADC_ALERT_R
  SDA  = SMB_INA230_3_3V3AUX_SDA_R1
  SCL  = SMB_INA230_3_3V3AUX_SCL_R1
  NC0  = NC_INA230_3_NC0
  NC1  = NC_INA230_3_NC1
  NC2  = NC_INA230_3_NC2
  VS  = P3V3_AUX
  GND  = GND
  \bus\  = P3V3_OCP_V3_2_R
  \in-\  = VSENSE_P12V_INA230_3_INN
  \in+\  = VSENSE_P12V_INA230_3_INP
  NC3  = NC_INA230_3_NC3
  NC4  = NC_INA230_3_NC4
  NC5  = NC_INA230_3_NC5
  TH  = GND

(kicad_pcb
	(version 20260206)
	(generator "pcbnew")
	(generator_version "10.0")
	(general
		(thickness 1.6)
		(legacy_teardrops no)
	)
	(paper "A4")
	(title_block
		(title "03242023_DA0F0TMBIJ0_F0T_Motherboard_J_brd_V01_OCP.brd")
		(comment 1 "Grand Teton / footprints 3957-3957 of 6105")
	)
	(layers
		(0 "F.Cu" signal "TOP")
		(4 "In1.Cu" signal "GND")
		(6 "In2.Cu" signal "IN1")
		(8 "In3.Cu" signal "GND1")
		(10 "In4.Cu" signal "IN2")
		(12 "In5.Cu" signal "GND2")
		(14 "In6.Cu" signal "IN3")
		(16 "In7.Cu" signal "GND3")
		(18 "In8.Cu" signal "VCC")
		(20 "In9.Cu" signal "VCC1")
		(22 "In10.Cu" signal "GND4")
		(24 "In11.Cu" signal "IN4")
		(26 "In12.Cu" signal "GND5")
		(28 "In13.Cu" signal "IN5")
		(30 "In14.Cu" signal "GND6")
		(32 "In15.Cu" signal "IN6")
		(34 "In16.Cu" signal "GND7")
		(2 "B.Cu" signal "BOTTOM")
		(9 "F.Adhes" user "F.Adhesive")
		(11 "B.Adhes" user "B.Adhesive")
		(13 "F.Paste" user "Package Geometry/Pastemask Top")
		(15 "B.Paste" user "Package Geometry/Pastemask Bottom")
		(5 "F.SilkS" user "Ref Des/Silkscreen Top")
		(7 "B.SilkS" user "Ref Des/Silkscreen Bottom")
		(1 "F.Mask" user "Board Geometry/Soldermask Top")
		(3 "B.Mask" user "Board Geometry/Soldermask Bottom")
		(17 "Dwgs.User" user "User.Drawings")
		(19 "Cmts.User" user "User.Comments")
		(21 "Eco1.User" user "User.Eco1")
		(23 "Eco2.User" user "User.Eco2")
		(25 "Edge.Cuts" user "Board Geometry/Outline")
		(27 "Margin" user)
		(31 "F.CrtYd" user "Package Geometry/Place Bound Top")
		(29 "B.CrtYd" user "Package Geometry/Place Bound Bottom")
		(35 "F.Fab" user "Ref Des/Assembly Top")
		(33 "B.Fab" user "Ref Des/Assembly Bottom")
	)
	(footprint ""
		(layer "F.Cu")
		(at 72.708262 -39.319962)
		(property "Reference" "U263"
			(at 2.341626 -3.780282 0)
			(unlocked yes)
			(layer "F.SilkS")
			(effects
				(font
					(size 0.7874 0.5842)
					(thickness 0.1524)
				)
			)
		)
		(property "Value" ""
			(at 0 0 0)
			(layer "F.Fab")
			(effects
				(font
					(size 1.27 1.27)
				)
			)
		)
		(duplicate_pad_numbers_are_jumpers no)
		(fp_line
			(start -1.500124 -1.500124)
			(end -1.004062 -1.500124)
			(stroke
				(width 0.1524)
				(type default)
			)
			(layer "F.SilkS")
		)
		(fp_line
			(start -1.500124 -1.004062)
			(end -1.500124 -1.500124)
			(stroke
				(width 0.1524)
				(type default)
			)
			(layer "F.SilkS")
		)
		(fp_line
			(start -1.500124 1.500124)
			(end -1.500124 1.004062)
			(stroke
				(width 0.1524)
				(type default)
			)
			(layer "F.SilkS")
		)
		(fp_line
			(start -1.004062 1.500124)
			(end -1.500124 1.500124)
			(stroke
				(width 0.1524)
				(type default)
			)
			(layer "F.SilkS")
		)
		(fp_line
			(start 1.004062 -1.500124)
			(end 1.500124 -1.500124)
			(stroke
				(width 0.1524)
				(type default)
			)
			(layer "F.SilkS")
		)
		(fp_line
			(start 1.500124 -1.500124)
			(end 1.500124 -1.004062)
			(stroke
				(width 0.1524)
				(type default)
			)
			(layer "F.SilkS")
		)
		(fp_line
			(start 1.500124 1.004062)
			(end 1.500124 1.500124)
			(stroke
				(width 0.1524)
				(type default)
			)
			(layer "F.SilkS")
		)
		(fp_line
			(start 1.500124 1.500124)
			(end 1.004062 1.500124)
			(stroke
				(width 0.1524)
				(type default)
			)
			(layer "F.SilkS")
		)
		(fp_poly
			(pts
				(xy -1.50241 -2.181098) (xy -1.894586 -1.396492) (xy -2.286762 -2.181098)
			)
			(stroke
				(width 0)
				(type default)
			)
			(fill yes)
			(layer "F.SilkS")
		)
		(fp_line
			(start -1.500124 -1.500124)
			(end 1.500124 -1.500124)
			(stroke
				(width 0.1)
				(type default)
			)
			(layer "F.Fab")
		)
		(fp_line
			(start -1.500124 1.500124)
			(end -1.500124 -1.500124)
			(stroke
				(width 0.1)
				(type default)
			)
			(layer "F.Fab")
		)
		(fp_line
			(start 1.500124 -1.500124)
			(end 1.500124 1.500124)
			(stroke
				(width 0.1)
				(type default)
			)
			(layer "F.Fab")
		)
		(fp_line
			(start 1.500124 1.500124)
			(end -1.500124 1.500124)
			(stroke
				(width 0.1)
				(type default)
			)
			(layer "F.Fab")
		)
		(fp_poly
			(pts
				(xy -2.847848 -1.258062) (xy -2.847848 -0.242062) (xy -1.831848 -0.750062)
			)
			(stroke
				(width 0)
				(type default)
			)
			(fill yes)
			(layer "F.Fab")
		)
		(pad "1" smd rect
			(at -1.400048 -0.750062 270)
			(size 0.2286 0.6096)
			(layers "F.Cu" "F.Mask" "F.Paste")
			(net "INA230_3_A1")
		)
		(pad "2" smd rect
			(at -1.400048 -0.249936 270)
			(size 0.2286 0.6096)
			(layers "F.Cu" "F.Mask" "F.Paste")
			(net "INA230_3_A0")
		)
		(pad "3" smd rect
			(at -1.400048 0.249936 270)
			(size 0.2286 0.6096)
			(layers "F.Cu" "F.Mask" "F.Paste")
			(net "OCP_V3_2_P3V3_ADC_ALERT_R")
		)
		(pad "4" smd rect
			(at -1.400048 0.750062 270)
			(size 0.2286 0.6096)
			(layers "F.Cu" "F.Mask" "F.Paste")
			(net "SMB_INA230_3_3V3AUX_SDA_R1")
		)
		(pad "5" smd rect
			(at -0.750062 1.400048)
			(size 0.2286 0.6096)
			(layers "F.Cu" "F.Mask" "F.Paste")
			(net "SMB_INA230_3_3V3AUX_SCL_R1")
		)
		(pad "6" smd rect
			(at -0.249936 1.400048)
			(size 0.2286 0.6096)
			(layers "F.Cu" "F.Mask" "F.Paste")
			(net "NC_INA230_3_NC0")
		)
		(pad "7" smd rect
			(at 0.249936 1.400048)
			(size 0.2286 0.6096)
			(layers "F.Cu" "F.Mask" "F.Paste")
			(net "NC_INA230_3_NC1")
		)
		(pad "8" smd rect
			(at 0.750062 1.400048)
			(size 0.2286 0.6096)
			(layers "F.Cu" "F.Mask" "F.Paste")
			(net "NC_INA230_3_NC2")
		)
		(pad "9" smd rect
			(at 1.400048 0.750062 270)
			(size 0.2286 0.6096)
			(layers "F.Cu" "F.Mask" "F.Paste")
			(net "P3V3_AUX")
		)
		(pad "10" smd rect
			(at 1.400048 0.249936 270)
			(size 0.2286 0.6096)
			(layers "F.Cu" "F.Mask" "F.Paste")
			(net "GND")
		)
		(pad "11" smd rect
			(at 1.400048 -0.249936 270)
			(size 0.2286 0.6096)
			(layers "F.Cu" "F.Mask" "F.Paste")
			(net "P3V3_OCP_V3_2_R")
		)
		(pad "12" smd rect
			(at 1.400048 -0.750062 270)
			(size 0.2286 0.6096)
			(layers "F.Cu" "F.Mask" "F.Paste")
			(net "VSENSE_P12V_INA230_3_INN")
		)
		(pad "13" smd rect
			(at 0.750062 -1.400048)
			(size 0.2286 0.6096)
			(layers "F.Cu" "F.Mask" "F.Paste")
			(net "VSENSE_P12V_INA230_3_INP")
		)
		(pad "14" smd rect
			(at 0.249936 -1.400048)
			(size 0.2286 0.6096)
			(layers "F.Cu" "F.Mask" "F.Paste")
			(net "NC_INA230_3_NC3")
		)
		(pad "15" smd rect
			(at -0.249936 -1.400048)
			(size 0.2286 0.6096)
			(layers "F.Cu" "F.Mask" "F.Paste")
			(net "NC_INA230_3_NC4")
		)
		(pad "16" smd rect
			(at -0.750062 -1.400048)
			(size 0.2286 0.6096)
			(layers "F.Cu" "F.Mask" "F.Paste")
			(net "NC_INA230_3_NC5")
		)
		(pad "TH" smd rect
			(at 0 0)
			(size 1.7018 1.7018)
			(layers "F.Cu" "F.Mask" "F.Paste")
			(net "GND")
		)
		(zone
			(layer "F.Cu")
			(hatch none 0.5)
			(connect_pads
				(clearance 0)
			)
			(min_thickness 0.25)
			(keepout
				(tracks not_allowed)
				(vias allowed)
				(pads allowed)
				(copperpour not_allowed)
				(footprints allowed)
			)
			(placement
				(enabled no)
				(sheetname "")
			)
			(fill
				(thermal_gap 0.5)
				(thermal_bridge_width 0.5)
				(island_removal_mode 0)
			)
			(polygon
				(pts
					(xy 71.663814 -39.345362) (xy 71.663814 -40.36441) (xy 73.75271 -40.36441) (xy 73.75271 -38.275514)
					(xy 71.663814 -38.275514) (xy 71.663814 -39.319962) (xy 71.806562 -39.319962) (xy 71.806562 -38.418262)
					(xy 73.609962 -38.418262) (xy 73.609962 -40.221662) (xy 71.806562 -40.221662) (xy 71.806562 -39.345362)
				)
			)
		)
	)
)
